# T6G (Grand Teton) — schematic netlist excerpt (pin names and nets, part order shuffled) for the footprints in the layout excerpt that follows; sources: Cadence DE-HDL packaged netlist, KiCad conversion of 04192023_DAF0TMB3IC0_F0TG_MB_C_brd_V02_OCP.brd

J35  SCONN168_ME1016810202011  IO  pkg CON_F168S2H7D_P0-6W2-95_LUH  page 137
  GND_A1  = GND
  GND_A2  = GND
  GND_A3  = GND
  GND_A4  = GND
  GND_A5  = GND
  GND_A6  = GND
  SMCLK  = SMB_OCP_V3_2_3V3AUX_BUF_R_SCL
  SMDAT  = SMB_OCP_V3_2_3V3AUX_BUF_R_SDA
  \smrst#\  = RST_SMB_OCP_V3_2_N
  \prsnta#\  = OCP_V3_2_PRSNTA_R_N
  \perst1#\  = RST_PERST1_OCP_V3_2_N
  \prsntb2#\  = OCP_V3_2_PRSNT2_R_N
  GND_A13  = GND
  REFCLKN1  = CLK_100M_CPU1_CLK03_DN
  REFCLKP1  = CLK_100M_CPU1_CLK03_DP
  GND_A16  = GND
  PERN0  = P5E_CPU1_G1_RX_DN<0>
  PERP0  = P5E_CPU1_G1_RX_DP<0>
  GND_A19  = GND
  PERN1  = P5E_CPU1_G1_RX_DN<1>
  PERP1  = P5E_CPU1_G1_RX_DP<1>
  GND_A22  = GND
  PERN2  = P5E_CPU1_G1_RX_DN<2>
  PERP2  = P5E_CPU1_G1_RX_DP<2>
  GND_A25  = GND
  PERN3  = P5E_CPU1_G1_RX_DN<3>
  PERP3  = P5E_CPU1_G1_RX_DP<3>
  GND_A28  = GND
  GND_A29  = GND
  PERN4  = P5E_CPU1_G1_RX_DN<4>
  PERP4  = P5E_CPU1_G1_RX_DP<4>
  GND_A32  = GND
  PERN5  = P5E_CPU1_G1_RX_DN<5>
  PERP5  = P5E_CPU1_G1_RX_DP<5>
  GND_A35  = GND
  PERN6  = P5E_CPU1_G1_RX_DN<6>
  PERP6  = P5E_CPU1_G1_RX_DP<6>
  GND_A38  = GND
  PERN7  = P5E_CPU1_G1_RX_DN<7>
  PERP7  = P5E_CPU1_G1_RX_DP<7>
  GND_A41  = GND
  \prsntb1#\  = OCP_V3_2_PRSNT1_R_N
  GND_A43  = GND
  PERN8  = P5E_CPU1_G1_RX_DN<8>
  PERP8  = P5E_CPU1_G1_RX_DP<8>
  GND_A46  = GND
  PERN9  = P5E_CPU1_G1_RX_DN<9>
  PERP9  = P5E_CPU1_G1_RX_DP<9>
  GND_A49  = GND
  PERN10  = P5E_CPU1_G1_RX_DN<10>
  PERP10  = P5E_CPU1_G1_RX_DP<10>
  GND_A52  = GND
  PERN11  = P5E_CPU1_G1_RX_DN<11>
  PERP11  = P5E_CPU1_G1_RX_DP<11>
  GND_A55  = GND
  PERN12  = P5E_CPU1_G1_RX_DN<12>
  PERP12  = P5E_CPU1_G1_RX_DP<12>
  GND_A58  = GND
  PERN13  = P5E_CPU1_G1_RX_DN<13>
  PERP13  = P5E_CPU1_G1_RX_DP<13>
  GND_A61  = GND
  PERN14  = P5E_CPU1_G1_RX_DN<14>
  PERP14  = P5E_CPU1_G1_RX_DP<14>
  GND_A64  = GND
  PERN15  = P5E_CPU1_G1_RX_DN<15>
  PERP15  = P5E_CPU1_G1_RX_DP<15>
  GND_A67  = GND
  USB_DATN  = USB2_P10_DN
  USB_DATP  = USB2_P10_DP
  \pwrbrk0#\  = OCP_V3_2_PWRBRK_N
  \+12v_edge_b1\  = P12V_OCP_V3_2_R
  \+12v_edge_b2\  = P12V_OCP_V3_2_R
  \+12v_edge_b3\  = P12V_OCP_V3_2_R
  \+12v_edge_b4\  = P12V_OCP_V3_2_R
  \+12v_edge_b5\  = P12V_OCP_V3_2_R
  \+12v_edge_b6\  = P12V_OCP_V3_2_R
  \bif0#\  = OCP_V3_2_BIF0_R_N
  \bif1#\  = OCP_V3_2_BIF1_R_N
  \bif2#\  = OCP_V3_2_BIF2_R_N
  \perst0#\  = RST_PERST0_OCP_V3_2_N
  \+3.3v_edge\  = P3V3_OCP_V3_2
  AUX_PWR_EN  = OCP_V3_2_AUX_PWR_EN_R
  GND_B13  = GND
  REFCLKN0  = CLK_100M_CPU1_CLK02_DN
  REFCLKP0  = CLK_100M_CPU1_CLK02_DP
  GND_B16  = GND
  PETN0  = P5E_CPU1_G1_TX_C_DP<0>
  PETP0  = P5E_CPU1_G1_TX_C_DN<0>
  GND_B19  = GND
  PETN1  = P5E_CPU1_G1_TX_C_DP<1>
  PETP1  = P5E_CPU1_G1_TX_C_DN<1>
  GND_B22  = GND
  PETN2  = P5E_CPU1_G1_TX_C_DP<2>
  PETP2  = P5E_CPU1_G1_TX_C_DN<2>
  GND_B25  = GND
  PETN3  = P5E_CPU1_G1_TX_C_DP<3>
  PETP3  = P5E_CPU1_G1_TX_C_DN<3>
  GND_B28  = GND
  GND_B29  = GND
  PETN4  = P5E_CPU1_G1_TX_C_DP<4>
  PETP4  = P5E_CPU1_G1_TX_C_DN<4>
  GND_B32  = GND
  PETN5  = P5E_CPU1_G1_TX_C_DP<5>
  PETP5  = P5E_CPU1_G1_TX_C_DN<5>
  GND_B35  = GND
  PETN6  = P5E_CPU1_G1_TX_C_DP<6>
  PETP6  = P5E_CPU1_G1_TX_C_DN<6>
  GND_B38  = GND
  PETN7  = P5E_CPU1_G1_TX_C_DP<7>
  PETP7  = P5E_CPU1_G1_TX_C_DN<7>
  GND_B41  = GND
  \prsntb0#\  = OCP_V3_2_PRSNT0_R_N
  GND_B43  = GND
  PETN8  = P5E_CPU1_G1_TX_C_DP<8>
  PETP8  = P5E_CPU1_G1_TX_C_DN<8>
  GND_B46  = GND
  PETN9  = P5E_CPU1_G1_TX_C_DP<9>
  PETP9  = P5E_CPU1_G1_TX_C_DN<9>
  GND_B49  = GND
  PETN10  = P5E_CPU1_G1_TX_C_DP<10>
  PETP10  = P5E_CPU1_G1_TX_C_DN<10>
  GND_B52  = GND
  PETN11  = P5E_CPU1_G1_TX_C_DP<11>
  PETP11  = P5E_CPU1_G1_TX_C_DN<11>
  GND_B55  = GND
  PETN12  = P5E_CPU1_G1_TX_C_DP<12>
  PETP12  = P5E_CPU1_G1_TX_C_DN<12>
  GND_B58  = GND
  PETN13  = P5E_CPU1_G1_TX_C_DP<13>
  PETP13  = P5E_CPU1_G1_TX_C_DN<13>
  GND_B61  = GND
  PETN14  = P5E_CPU1_G1_TX_C_DP<14>
  PETP14  = P5E_CPU1_G1_TX_C_DN<14>
  GND_B64  = GND
  PETN15  = P5E_CPU1_G1_TX_C_DP<15>
  PETP15  = P5E_CPU1_G1_TX_C_DN<15>
  GND_B67  = GND
  RFU1_NC_B68  = TP_OCP_V3_2_B68
  RFU1_NC_B69  = TP_OCP_V3_2_B69
  \prsntb3#\  = OCP_V3_2_PRSNT3_R_N
  G1  = GND
  G2  = GND
  G3  = GND
  G4  = GND
  G5  = GND
  \perst2#\  = RST_PERST2_OCP_V3_2_N
  \perst3#\  = RST_PERST3_OCP_V3_2_N
  \wake#\  = IRQ_LVC3_OCP_V3_2_WAKE_N
  RBT_ARB_IN  = OCP_V3_2_ISO1_RBT_ARB_IN
  RBT_ARB_OUT  = OCP_V3_2_ISO2_RBT_ARB_OUT
  SLOT_ID1  = OCP_V3_2_ID1
  RBT_TX_EN  = NCSI_OCP_V3_2_TX_EN
  RBT_TXD1  = NCSI_OCP_V3_2_TXD1
  RBT_TXD0  = NCSI_OCP_V3_2_TXD0
  GND_OA10  = GND
  REFCLKN3  = CLK_100M_CPU1_CLK05_DN
  REFCLKP3  = CLK_100M_CPU1_CLK05_DP
  GND_OA13  = GND
  RBT_CLK_IN  = CLK_50M_NCSI_OCP_V3_2_ISO
  NIC_PWR_GOOD  = FM_OCP_V3_2_PWR_GOOD
  MAIN_PWR_EN  = OCP_V3_2_MAIN_PWR_EN_R
  \ld#\  = SGPIO_OCP_V3_2_LD_N
  DATA_IN  = SGPIO_OCP_V3_2_DATAIN
  DATA_OUT  = SGPIO_OCP_V3_2_DATAOUT
  CLK  = SGPIO_OCP_V3_2_CLK
  SLOT_ID0  = OCP_V3_2_ID0
  RBT_RXD1  = NCSI_OCP_V3_2_RXD1
  RBT_RXD0  = NCSI_OCP_V3_2_RXD0
  GND_OB10  = GND
  REFCLKN2  = CLK_100M_CPU1_CLK04_DN
  REFCLKP2  = CLK_100M_CPU1_CLK04_DP
  GND_OB13  = GND
  RBT_CRS_DV  = NCSI_OCP_V3_2_CRS_DV

(kicad_pcb
	(version 20260206)
	(generator "pcbnew")
	(generator_version "10.0")
	(general
		(thickness 1.6)
		(legacy_teardrops no)
	)
	(paper "A4")
	(title_block
		(title "04192023_DAF0TMB3IC0_F0TG_MB_C_brd_V02_OCP.brd")
		(comment 1 "Grand Teton / footprint 4922 of 8354 (J35), pads 1-45 of 175")
	)
	(layers
		(0 "F.Cu" signal "TOP")
		(4 "In1.Cu" signal "GND")
		(6 "In2.Cu" signal "IN1")
		(8 "In3.Cu" signal "GND1")
		(10 "In4.Cu" signal "IN2")
		(12 "In5.Cu" signal "GND2")
		(14 "In6.Cu" signal "IN3")
		(16 "In7.Cu" signal "GND3")
		(18 "In8.Cu" signal "VCC")
		(20 "In9.Cu" signal "VCC1")
		(22 "In10.Cu" signal "GND4")
		(24 "In11.Cu" signal "IN4")
		(26 "In12.Cu" signal "GND5")
		(28 "In13.Cu" signal "IN5")
		(30 "In14.Cu" signal "GND6")
		(32 "In15.Cu" signal "IN6")
		(34 "In16.Cu" signal "GND7")
		(2 "B.Cu" signal "BOTTOM")
		(9 "F.Adhes" user "F.Adhesive")
		(11 "B.Adhes" user "B.Adhesive")
		(13 "F.Paste" user "Package Geometry/Pastemask Top")
		(15 "B.Paste" user "Package Geometry/Pastemask Bottom")
		(5 "F.SilkS" user "Ref Des/Silkscreen Top")
		(7 "B.SilkS" user "Ref Des/Silkscreen Bottom")
		(1 "F.Mask" user "Board Geometry/Soldermask Top")
		(3 "B.Mask" user "Board Geometry/Soldermask Bottom")
		(17 "Dwgs.User" user "User.Drawings")
		(19 "Cmts.User" user "User.Comments")
		(21 "Eco1.User" user "User.Eco1")
		(23 "Eco2.User" user "User.Eco2")
		(25 "Edge.Cuts" user "Board Geometry/Outline")
		(27 "Margin" user)
		(31 "F.CrtYd" user "Package Geometry/Place Bound Top")
		(29 "B.CrtYd" user "Package Geometry/Place Bound Bottom")
		(35 "F.Fab" user "Ref Des/Assembly Top")
		(33 "B.Fab" user "Ref Des/Assembly Bottom")
	)
	(footprint ""
		(layer "F.Cu")
		(at 47.401988 -5.569966 -90)
		(property "Reference" "J35"
			(at -8.0772 -20.659598 0)
			(unlocked yes)
			(layer "F.SilkS")
			(effects
				(font
					(size 0.7874 0.5842)
					(thickness 0.1524)
				)
				(justify left)
			)
		)
		(property "Value" ""
			(at 0 0 270)
			(layer "F.Fab")
			(effects
				(font
					(size 1.27 1.27)
				)
			)
		)
		(duplicate_pad_numbers_are_jumpers no)
		(pad "" np_thru_hole circle
			(at -0.599948 -32.079946 180)
			(size 1.1176 1.1176)
			(drill 1.1176)
			(layers "*.Cu" "*.Mask")
			(clearance 0.381)
			(thermal_gap 0.381)
		)
		(pad "" np_thru_hole circle
			(at 0.40005 32.085026 180)
			(size 1.1176 1.1176)
			(drill 1.1176)
			(layers "*.Cu" "*.Mask")
			(clearance 0.381)
			(thermal_gap 0.381)
		)
		(pad "A1" smd rect
			(at -2.750058 -18.465038 180)
			(size 0.381 1.4478)
			(layers "F.Cu" "F.Mask" "F.Paste")
			(net "GND")
		)
		(pad "A2" smd rect
			(at -2.750058 -17.86509 180)
			(size 0.381 1.4478)
			(layers "F.Cu" "F.Mask" "F.Paste")
			(net "GND")
		)
		(pad "A3" smd rect
			(at -2.750058 -17.264888 180)
			(size 0.381 1.4478)
			(layers "F.Cu" "F.Mask" "F.Paste")
			(net "GND")
		)
		(pad "A4" smd rect
			(at -2.750058 -16.66494 180)
			(size 0.381 1.4478)
			(layers "F.Cu" "F.Mask" "F.Paste")
			(net "GND")
		)
		(pad "A5" smd rect
			(at -2.750058 -16.064992 180)
			(size 0.381 1.4478)
			(layers "F.Cu" "F.Mask" "F.Paste")
			(net "GND")
		)
		(pad "A6" smd rect
			(at -2.750058 -15.465044 180)
			(size 0.381 1.4478)
			(layers "F.Cu" "F.Mask" "F.Paste")
			(net "GND")
		)
		(pad "A7" smd rect
			(at -2.750058 -14.865096 180)
			(size 0.381 1.4478)
			(layers "F.Cu" "F.Mask" "F.Paste")
			(net "SMB_OCP_V3_2_3V3AUX_BUF_R_SCL")
		)
		(pad "A8" smd rect
			(at -2.750058 -14.264894 180)
			(size 0.381 1.4478)
			(layers "F.Cu" "F.Mask" "F.Paste")
			(net "SMB_OCP_V3_2_3V3AUX_BUF_R_SDA")
		)
		(pad "A9" smd rect
			(at -2.750058 -13.664946 180)
			(size 0.381 1.4478)
			(layers "F.Cu" "F.Mask" "F.Paste")
			(net "RST_SMB_OCP_V3_2_N")
		)
		(pad "A10" smd rect
			(at -2.750058 -13.064998 180)
			(size 0.381 1.4478)
			(layers "F.Cu" "F.Mask" "F.Paste")
			(net "OCP_V3_2_PRSNTA_R_N")
		)
		(pad "A11" smd rect
			(at -2.750058 -12.46505 180)
			(size 0.381 1.4478)
			(layers "F.Cu" "F.Mask" "F.Paste")
			(net "RST_PERST1_OCP_V3_2_N")
		)
		(pad "A12" smd rect
			(at -2.750058 -11.865102 180)
			(size 0.381 1.4478)
			(layers "F.Cu" "F.Mask" "F.Paste")
			(net "OCP_V3_2_PRSNT2_R_N")
		)
		(pad "A13" smd rect
			(at -2.750058 -11.2649 180)
			(size 0.381 1.4478)
			(layers "F.Cu" "F.Mask" "F.Paste")
			(net "GND")
		)
		(pad "A14" smd rect
			(at -2.750058 -10.664952 180)
			(size 0.381 1.4478)
			(layers "F.Cu" "F.Mask" "F.Paste")
			(net "CLK_100M_CPU1_CLK03_DN")
		)
		(pad "A15" smd rect
			(at -2.750058 -10.065004 180)
			(size 0.381 1.4478)
			(layers "F.Cu" "F.Mask" "F.Paste")
			(net "CLK_100M_CPU1_CLK03_DP")
		)
		(pad "A16" smd rect
			(at -2.750058 -9.465056 180)
			(size 0.381 1.4478)
			(layers "F.Cu" "F.Mask" "F.Paste")
			(net "GND")
		)
		(pad "A17" smd rect
			(at -2.750058 -8.865108 180)
			(size 0.381 1.4478)
			(layers "F.Cu" "F.Mask" "F.Paste")
			(net "P5E_CPU1_G1_RX_DN<0>")
		)
		(pad "A18" smd rect
			(at -2.750058 -8.264906 180)
			(size 0.381 1.4478)
			(layers "F.Cu" "F.Mask" "F.Paste")
			(net "P5E_CPU1_G1_RX_DP<0>")
		)
		(pad "A19" smd rect
			(at -2.750058 -7.664958 180)
			(size 0.381 1.4478)
			(layers "F.Cu" "F.Mask" "F.Paste")
			(net "GND")
		)
		(pad "A20" smd rect
			(at -2.750058 -7.06501 180)
			(size 0.381 1.4478)
			(layers "F.Cu" "F.Mask" "F.Paste")
			(net "P5E_CPU1_G1_RX_DN<1>")
		)
		(pad "A21" smd rect
			(at -2.750058 -6.465062 180)
			(size 0.381 1.4478)
			(layers "F.Cu" "F.Mask" "F.Paste")
			(net "P5E_CPU1_G1_RX_DP<1>")
		)
		(pad "A22" smd rect
			(at -2.750058 -5.865114 180)
			(size 0.381 1.4478)
			(layers "F.Cu" "F.Mask" "F.Paste")
			(net "GND")
		)
		(pad "A23" smd rect
			(at -2.750058 -5.264912 180)
			(size 0.381 1.4478)
			(layers "F.Cu" "F.Mask" "F.Paste")
			(net "P5E_CPU1_G1_RX_DN<2>")
		)
		(pad "A24" smd rect
			(at -2.750058 -4.664964 180)
			(size 0.381 1.4478)
			(layers "F.Cu" "F.Mask" "F.Paste")
			(net "P5E_CPU1_G1_RX_DP<2>")
		)
		(pad "A25" smd rect
			(at -2.750058 -4.065016 180)
			(size 0.381 1.4478)
			(layers "F.Cu" "F.Mask" "F.Paste")
			(net "GND")
		)
		(pad "A26" smd rect
			(at -2.750058 -3.465068 180)
			(size 0.381 1.4478)
			(layers "F.Cu" "F.Mask" "F.Paste")
			(net "P5E_CPU1_G1_RX_DN<3>")
		)
		(pad "A27" smd rect
			(at -2.750058 -2.86512 180)
			(size 0.381 1.4478)
			(layers "F.Cu" "F.Mask" "F.Paste")
			(net "P5E_CPU1_G1_RX_DP<3>")
		)
		(pad "A28" smd rect
			(at -2.750058 -2.264918 180)
			(size 0.381 1.4478)
			(layers "F.Cu" "F.Mask" "F.Paste")
			(net "GND")
		)
		(pad "A29" smd rect
			(at -2.750058 1.74498 180)
			(size 0.381 1.4478)
			(layers "F.Cu" "F.Mask" "F.Paste")
			(net "GND")
		)
		(pad "A30" smd rect
			(at -2.750058 2.344928 180)
			(size 0.381 1.4478)
			(layers "F.Cu" "F.Mask" "F.Paste")
			(net "P5E_CPU1_G1_RX_DN<4>")
		)
		(pad "A31" smd rect
			(at -2.750058 2.944876 180)
			(size 0.381 1.4478)
			(layers "F.Cu" "F.Mask" "F.Paste")
			(net "P5E_CPU1_G1_RX_DP<4>")
		)
		(pad "A32" smd rect
			(at -2.750058 3.545078 180)
			(size 0.381 1.4478)
			(layers "F.Cu" "F.Mask" "F.Paste")
			(net "GND")
		)
		(pad "A33" smd rect
			(at -2.750058 4.145026 180)
			(size 0.381 1.4478)
			(layers "F.Cu" "F.Mask" "F.Paste")
			(net "P5E_CPU1_G1_RX_DN<5>")
		)
		(pad "A34" smd rect
			(at -2.750058 4.744974 180)
			(size 0.381 1.4478)
			(layers "F.Cu" "F.Mask" "F.Paste")
			(net "P5E_CPU1_G1_RX_DP<5>")
		)
		(pad "A35" smd rect
			(at -2.750058 5.344922 180)
			(size 0.381 1.4478)
			(layers "F.Cu" "F.Mask" "F.Paste")
			(net "GND")
		)
		(pad "A36" smd rect
			(at -2.750058 5.945124 180)
			(size 0.381 1.4478)
			(layers "F.Cu" "F.Mask" "F.Paste")
			(net "P5E_CPU1_G1_RX_DN<6>")
		)
		(pad "A37" smd rect
			(at -2.750058 6.545072 180)
			(size 0.381 1.4478)
			(layers "F.Cu" "F.Mask" "F.Paste")
			(net "P5E_CPU1_G1_RX_DP<6>")
		)
		(pad "A38" smd rect
			(at -2.750058 7.14502 180)
			(size 0.381 1.4478)
			(layers "F.Cu" "F.Mask" "F.Paste")
			(net "GND")
		)
		(pad "A39" smd rect
			(at -2.750058 7.744968 180)
			(size 0.381 1.4478)
			(layers "F.Cu" "F.Mask" "F.Paste")
			(net "P5E_CPU1_G1_RX_DN<7>")
		)
		(pad "A40" smd rect
			(at -2.750058 8.344916 180)
			(size 0.381 1.4478)
			(layers "F.Cu" "F.Mask" "F.Paste")
			(net "P5E_CPU1_G1_RX_DP<7>")
		)
		(pad "A41" smd rect
			(at -2.750058 8.945118 180)
			(size 0.381 1.4478)
			(layers "F.Cu" "F.Mask" "F.Paste")
			(net "GND")
		)
		(pad "A42" smd rect
			(at -2.750058 9.545066 180)
			(size 0.381 1.4478)
			(layers "F.Cu" "F.Mask" "F.Paste")
			(net "OCP_V3_2_PRSNT1_R_N")
		)
		(pad "A43" smd rect
			(at -2.750058 14.454886 180)
			(size 0.381 1.4478)
			(layers "F.Cu" "F.Mask" "F.Paste")
			(net "GND")
		)
	)
)
